# S9S_MB_2U (Grand Teton) — schematic netlist excerpt (pin names and nets, part order shuffled) for the footprints in the layout excerpt that follows; sources: Cadence DE-HDL packaged netlist, KiCad conversion of 03242023_DA0F0TMBIJ0_F0T_Motherboard_J_brd_V01_OCP.brd

R944  Q_RES  10K 1% CHIP  pkg 0402LF  page 115 : A = P3V3_AUX ; B = PWRGD_FAIL_CPU1_AB_R1
R44  Q_RES  23.2K 1% CHIP  pkg 0402LF  page 100 : A = PD_CHB_CPU1_DIMM1_SAA ; B = GND

(kicad_pcb
	(version 20260206)
	(generator "pcbnew")
	(generator_version "10.0")
	(general
		(thickness 1.6)
		(legacy_teardrops no)
	)
	(paper "A4")
	(title_block
		(title "03242023_DA0F0TMBIJ0_F0T_Motherboard_J_brd_V01_OCP.brd")
		(comment 1 "Grand Teton / footprints 5974-5975 of 6105")
	)
	(layers
		(0 "F.Cu" signal "TOP")
		(4 "In1.Cu" signal "GND")
		(6 "In2.Cu" signal "IN1")
		(8 "In3.Cu" signal "GND1")
		(10 "In4.Cu" signal "IN2")
		(12 "In5.Cu" signal "GND2")
		(14 "In6.Cu" signal "IN3")
		(16 "In7.Cu" signal "GND3")
		(18 "In8.Cu" signal "VCC")
		(20 "In9.Cu" signal "VCC1")
		(22 "In10.Cu" signal "GND4")
		(24 "In11.Cu" signal "IN4")
		(26 "In12.Cu" signal "GND5")
		(28 "In13.Cu" signal "IN5")
		(30 "In14.Cu" signal "GND6")
		(32 "In15.Cu" signal "IN6")
		(34 "In16.Cu" signal "GND7")
		(2 "B.Cu" signal "BOTTOM")
		(9 "F.Adhes" user "F.Adhesive")
		(11 "B.Adhes" user "B.Adhesive")
		(13 "F.Paste" user "Package Geometry/Pastemask Top")
		(15 "B.Paste" user "Package Geometry/Pastemask Bottom")
		(5 "F.SilkS" user "Ref Des/Silkscreen Top")
		(7 "B.SilkS" user "Ref Des/Silkscreen Bottom")
		(1 "F.Mask" user "Board Geometry/Soldermask Top")
		(3 "B.Mask" user "Board Geometry/Soldermask Bottom")
		(17 "Dwgs.User" user "User.Drawings")
		(19 "Cmts.User" user "User.Comments")
		(21 "Eco1.User" user "User.Eco1")
		(23 "Eco2.User" user "User.Eco2")
		(25 "Edge.Cuts" user "Board Geometry/Outline")
		(27 "Margin" user)
		(31 "F.CrtYd" user "Package Geometry/Place Bound Top")
		(29 "B.CrtYd" user "Package Geometry/Place Bound Bottom")
		(35 "F.Fab" user "Ref Des/Assembly Top")
		(33 "B.Fab" user "Ref Des/Assembly Bottom")
	)
	(footprint ""
		(layer "B.Cu")
		(at 64.990218 -318.962024 180)
		(property "Reference" "R944"
			(at 0 0 0)
			(layer "B.SilkS")
			(hide yes)
			(effects
				(font
					(size 1.27 1.27)
				)
				(justify mirror)
			)
		)
		(property "Value" ""
			(at 0 0 0)
			(layer "B.Fab")
			(effects
				(font
					(size 1.27 1.27)
				)
				(justify mirror)
			)
		)
		(duplicate_pad_numbers_are_jumpers no)
		(fp_line
			(start 0.7874 0.4064)
			(end 0.7874 -0.4064)
			(stroke
				(width 0.1524)
				(type default)
			)
			(layer "B.SilkS")
		)
		(fp_line
			(start 0.7874 -0.4064)
			(end -0.7874 -0.4064)
			(stroke
				(width 0.1524)
				(type default)
			)
			(layer "B.SilkS")
		)
		(fp_line
			(start -0.7874 0.4064)
			(end 0.7874 0.4064)
			(stroke
				(width 0.1524)
				(type default)
			)
			(layer "B.SilkS")
		)
		(fp_line
			(start -0.7874 -0.4064)
			(end -0.7874 0.4064)
			(stroke
				(width 0.1524)
				(type default)
			)
			(layer "B.SilkS")
		)
		(fp_line
			(start 0.67945 0.3048)
			(end 0.67945 -0.305054)
			(stroke
				(width 0.1)
				(type default)
			)
			(layer "B.Fab")
		)
		(fp_line
			(start 0.67945 -0.305054)
			(end 0.12065 -0.305054)
			(stroke
				(width 0.1)
				(type default)
			)
			(layer "B.Fab")
		)
		(fp_line
			(start 0.12065 0.3048)
			(end 0.67945 0.3048)
			(stroke
				(width 0.1)
				(type default)
			)
			(layer "B.Fab")
		)
		(fp_line
			(start 0.12065 0.2794)
			(end 0.12065 0.3048)
			(stroke
				(width 0.1)
				(type default)
			)
			(layer "B.Fab")
		)
		(fp_line
			(start 0.12065 -0.2794)
			(end -0.12065 -0.2794)
			(stroke
				(width 0.1)
				(type default)
			)
			(layer "B.Fab")
		)
		(fp_line
			(start 0.12065 -0.305054)
			(end 0.12065 -0.2794)
			(stroke
				(width 0.1)
				(type default)
			)
			(layer "B.Fab")
		)
		(fp_line
			(start -0.120396 0.3048)
			(end -0.120396 0.2794)
			(stroke
				(width 0.1)
				(type default)
			)
			(layer "B.Fab")
		)
		(fp_line
			(start -0.120396 0.2794)
			(end 0.12065 0.2794)
			(stroke
				(width 0.1)
				(type default)
			)
			(layer "B.Fab")
		)
		(fp_line
			(start -0.12065 -0.2794)
			(end -0.12065 -0.3048)
			(stroke
				(width 0.1)
				(type default)
			)
			(layer "B.Fab")
		)
		(fp_line
			(start -0.12065 -0.3048)
			(end -0.67945 -0.3048)
			(stroke
				(width 0.1)
				(type default)
			)
			(layer "B.Fab")
		)
		(fp_line
			(start -0.67945 0.3048)
			(end -0.120396 0.3048)
			(stroke
				(width 0.1)
				(type default)
			)
			(layer "B.Fab")
		)
		(fp_line
			(start -0.67945 -0.3048)
			(end -0.67945 0.3048)
			(stroke
				(width 0.1)
				(type default)
			)
			(layer "B.Fab")
		)
		(pad "1" smd circle
			(at 0.40005 0)
			(size 0 0)
			(layers "B.Cu" "B.Mask" "B.Paste")
			(net "P3V3_AUX")
		)
		(pad "2" smd circle
			(at -0.40005 0)
			(size 0 0)
			(layers "B.Cu" "B.Mask" "B.Paste")
			(net "PWRGD_FAIL_CPU1_AB_R1")
		)
	)
	(footprint ""
		(layer "B.Cu")
		(at 39.621206 -318.366648)
		(property "Reference" "R44"
			(at 0 0 0)
			(layer "B.SilkS")
			(hide yes)
			(effects
				(font
					(size 1.27 1.27)
				)
				(justify mirror)
			)
		)
		(property "Value" ""
			(at 0 0 0)
			(layer "B.Fab")
			(effects
				(font
					(size 1.27 1.27)
				)
				(justify mirror)
			)
		)
		(duplicate_pad_numbers_are_jumpers no)
		(fp_line
			(start -0.7874 -0.4064)
			(end -0.7874 0.4064)
			(stroke
				(width 0.1524)
				(type default)
			)
			(layer "B.SilkS")
		)
		(fp_line
			(start -0.7874 0.4064)
			(end 0.7874 0.4064)
			(stroke
				(width 0.1524)
				(type default)
			)
			(layer "B.SilkS")
		)
		(fp_line
			(start 0.7874 -0.4064)
			(end -0.7874 -0.4064)
			(stroke
				(width 0.1524)
				(type default)
			)
			(layer "B.SilkS")
		)
		(fp_line
			(start 0.7874 0.4064)
			(end 0.7874 -0.4064)
			(stroke
				(width 0.1524)
				(type default)
			)
			(layer "B.SilkS")
		)
		(fp_line
			(start -0.67945 -0.3048)
			(end -0.67945 0.3048)
			(stroke
				(width 0.1)
				(type default)
			)
			(layer "B.Fab")
		)
		(fp_line
			(start -0.67945 0.3048)
			(end -0.120396 0.3048)
			(stroke
				(width 0.1)
				(type default)
			)
			(layer "B.Fab")
		)
		(fp_line
			(start -0.12065 -0.3048)
			(end -0.67945 -0.3048)
			(stroke
				(width 0.1)
				(type default)
			)
			(layer "B.Fab")
		)
		(fp_line
			(start -0.12065 -0.2794)
			(end -0.12065 -0.3048)
			(stroke
				(width 0.1)
				(type default)
			)
			(layer "B.Fab")
		)
		(fp_line
			(start -0.120396 0.2794)
			(end 0.12065 0.2794)
			(stroke
				(width 0.1)
				(type default)
			)
			(layer "B.Fab")
		)
		(fp_line
			(start -0.120396 0.3048)
			(end -0.120396 0.2794)
			(stroke
				(width 0.1)
				(type default)
			)
			(layer "B.Fab")
		)
		(fp_line
			(start 0.12065 -0.305054)
			(end 0.12065 -0.2794)
			(stroke
				(width 0.1)
				(type default)
			)
			(layer "B.Fab")
		)
		(fp_line
			(start 0.12065 -0.2794)
			(end -0.12065 -0.2794)
			(stroke
				(width 0.1)
				(type default)
			)
			(layer "B.Fab")
		)
		(fp_line
			(start 0.12065 0.2794)
			(end 0.12065 0.3048)
			(stroke
				(width 0.1)
				(type default)
			)
			(layer "B.Fab")
		)
		(fp_line
			(start 0.12065 0.3048)
			(end 0.67945 0.3048)
			(stroke
				(width 0.1)
				(type default)
			)
			(layer "B.Fab")
		)
		(fp_line
			(start 0.67945 -0.305054)
			(end 0.12065 -0.305054)
			(stroke
				(width 0.1)
				(type default)
			)
			(layer "B.Fab")
		)
		(fp_line
			(start 0.67945 0.3048)
			(end 0.67945 -0.305054)
			(stroke
				(width 0.1)
				(type default)
			)
			(layer "B.Fab")
		)
		(pad "1" smd circle
			(at 0.40005 0 180)
			(size 0 0)
			(layers "B.Cu" "B.Mask" "B.Paste")
			(net "PD_CHB_CPU1_DIMM1_SAA")
		)
		(pad "2" smd circle
			(at -0.40005 0 180)
			(size 0 0)
			(layers "B.Cu" "B.Mask" "B.Paste")
			(net "GND")
		)
	)
)
